# S9S_MB_2U (Grand Teton) — schematic netlist excerpt (pin names and nets, part order shuffled) for the footprints in the layout excerpt that follows; sources: Cadence DE-HDL packaged netlist, KiCad conversion of 03242023_DA0F0TMBIJ0_F0T_Motherboard_J_brd_V01_OCP.brd

PR120  Q_RES  0 5% CHIP  pkg 0402LF  page 274 : A = SH_PVCCINFAON_CPU0 ; B = SH_PVCCINFAON_CPU0_R
R2304  Q_RES  10K 1% CHIP  pkg 0402LF  page 191 : A = P3V3_AUX ; B = E1S_0_PRSNT_N

(kicad_pcb
	(version 20260206)
	(generator "pcbnew")
	(generator_version "10.0")
	(general
		(thickness 1.6)
		(legacy_teardrops no)
	)
	(paper "A4")
	(title_block
		(title "03242023_DA0F0TMBIJ0_F0T_Motherboard_J_brd_V01_OCP.brd")
		(comment 1 "Grand Teton / footprints 2184-2185 of 6105")
	)
	(layers
		(0 "F.Cu" signal "TOP")
		(4 "In1.Cu" signal "GND")
		(6 "In2.Cu" signal "IN1")
		(8 "In3.Cu" signal "GND1")
		(10 "In4.Cu" signal "IN2")
		(12 "In5.Cu" signal "GND2")
		(14 "In6.Cu" signal "IN3")
		(16 "In7.Cu" signal "GND3")
		(18 "In8.Cu" signal "VCC")
		(20 "In9.Cu" signal "VCC1")
		(22 "In10.Cu" signal "GND4")
		(24 "In11.Cu" signal "IN4")
		(26 "In12.Cu" signal "GND5")
		(28 "In13.Cu" signal "IN5")
		(30 "In14.Cu" signal "GND6")
		(32 "In15.Cu" signal "IN6")
		(34 "In16.Cu" signal "GND7")
		(2 "B.Cu" signal "BOTTOM")
		(9 "F.Adhes" user "F.Adhesive")
		(11 "B.Adhes" user "B.Adhesive")
		(13 "F.Paste" user "Package Geometry/Pastemask Top")
		(15 "B.Paste" user "Package Geometry/Pastemask Bottom")
		(5 "F.SilkS" user "Ref Des/Silkscreen Top")
		(7 "B.SilkS" user "Ref Des/Silkscreen Bottom")
		(1 "F.Mask" user "Board Geometry/Soldermask Top")
		(3 "B.Mask" user "Board Geometry/Soldermask Bottom")
		(17 "Dwgs.User" user "User.Drawings")
		(19 "Cmts.User" user "User.Comments")
		(21 "Eco1.User" user "User.Eco1")
		(23 "Eco2.User" user "User.Eco2")
		(25 "Edge.Cuts" user "Board Geometry/Outline")
		(27 "Margin" user)
		(31 "F.CrtYd" user "Package Geometry/Place Bound Top")
		(29 "B.CrtYd" user "Package Geometry/Place Bound Bottom")
		(35 "F.Fab" user "Ref Des/Assembly Top")
		(33 "B.Fab" user "Ref Des/Assembly Bottom")
	)
	(footprint ""
		(layer "F.Cu")
		(at 429.28032 -140.654278 -90)
		(property "Reference" "PR120"
			(at 0 0 270)
			(layer "F.SilkS")
			(hide yes)
			(effects
				(font
					(size 1.27 1.27)
				)
			)
		)
		(property "Value" ""
			(at 0 0 270)
			(layer "F.Fab")
			(effects
				(font
					(size 1.27 1.27)
				)
			)
		)
		(duplicate_pad_numbers_are_jumpers no)
		(fp_line
			(start -0.7874 0.4064)
			(end -0.7874 -0.4064)
			(stroke
				(width 0.1524)
				(type default)
			)
			(layer "F.SilkS")
		)
		(fp_line
			(start 0.7874 0.4064)
			(end -0.7874 0.4064)
			(stroke
				(width 0.1524)
				(type default)
			)
			(layer "F.SilkS")
		)
		(fp_line
			(start -0.7874 -0.4064)
			(end 0.7874 -0.4064)
			(stroke
				(width 0.1524)
				(type default)
			)
			(layer "F.SilkS")
		)
		(fp_line
			(start 0.7874 -0.4064)
			(end 0.7874 0.4064)
			(stroke
				(width 0.1524)
				(type default)
			)
			(layer "F.SilkS")
		)
		(fp_line
			(start -0.67945 0.3048)
			(end -0.67945 -0.305054)
			(stroke
				(width 0.1)
				(type default)
			)
			(layer "F.Fab")
		)
		(fp_line
			(start -0.12065 0.3048)
			(end -0.67945 0.3048)
			(stroke
				(width 0.1)
				(type default)
			)
			(layer "F.Fab")
		)
		(fp_line
			(start 0.120396 0.3048)
			(end 0.120396 0.2794)
			(stroke
				(width 0.1)
				(type default)
			)
			(layer "F.Fab")
		)
		(fp_line
			(start 0.67945 0.3048)
			(end 0.120396 0.3048)
			(stroke
				(width 0.1)
				(type default)
			)
			(layer "F.Fab")
		)
		(fp_line
			(start -0.12065 0.2794)
			(end -0.12065 0.3048)
			(stroke
				(width 0.1)
				(type default)
			)
			(layer "F.Fab")
		)
		(fp_line
			(start 0.120396 0.2794)
			(end -0.12065 0.2794)
			(stroke
				(width 0.1)
				(type default)
			)
			(layer "F.Fab")
		)
		(fp_line
			(start -0.12065 -0.2794)
			(end 0.12065 -0.2794)
			(stroke
				(width 0.1)
				(type default)
			)
			(layer "F.Fab")
		)
		(fp_line
			(start 0.12065 -0.2794)
			(end 0.12065 -0.3048)
			(stroke
				(width 0.1)
				(type default)
			)
			(layer "F.Fab")
		)
		(fp_line
			(start 0.12065 -0.3048)
			(end 0.67945 -0.3048)
			(stroke
				(width 0.1)
				(type default)
			)
			(layer "F.Fab")
		)
		(fp_line
			(start 0.67945 -0.3048)
			(end 0.67945 0.3048)
			(stroke
				(width 0.1)
				(type default)
			)
			(layer "F.Fab")
		)
		(fp_line
			(start -0.67945 -0.305054)
			(end -0.12065 -0.305054)
			(stroke
				(width 0.1)
				(type default)
			)
			(layer "F.Fab")
		)
		(fp_line
			(start -0.12065 -0.305054)
			(end -0.12065 -0.2794)
			(stroke
				(width 0.1)
				(type default)
			)
			(layer "F.Fab")
		)
		(pad "1" smd circle
			(at -0.40005 0 270)
			(size 0 0)
			(layers "F.Cu" "F.Mask" "F.Paste")
			(net "SH_PVCCINFAON_CPU0")
		)
		(pad "2" smd circle
			(at 0.40005 0 270)
			(size 0 0)
			(layers "F.Cu" "F.Mask" "F.Paste")
			(net "SH_PVCCINFAON_CPU0_R")
		)
	)
	(footprint ""
		(layer "F.Cu")
		(at 136.668256 -68.445888 180)
		(property "Reference" "R2304"
			(at 0 0 180)
			(layer "F.SilkS")
			(hide yes)
			(effects
				(font
					(size 1.27 1.27)
				)
			)
		)
		(property "Value" ""
			(at 0 0 180)
			(layer "F.Fab")
			(effects
				(font
					(size 1.27 1.27)
				)
			)
		)
		(duplicate_pad_numbers_are_jumpers no)
		(fp_line
			(start 0.7874 0.4064)
			(end -0.7874 0.4064)
			(stroke
				(width 0.1524)
				(type default)
			)
			(layer "F.SilkS")
		)
		(fp_line
			(start 0.7874 -0.4064)
			(end 0.7874 0.4064)
			(stroke
				(width 0.1524)
				(type default)
			)
			(layer "F.SilkS")
		)
		(fp_line
			(start -0.7874 0.4064)
			(end -0.7874 -0.4064)
			(stroke
				(width 0.1524)
				(type default)
			)
			(layer "F.SilkS")
		)
		(fp_line
			(start -0.7874 -0.4064)
			(end 0.7874 -0.4064)
			(stroke
				(width 0.1524)
				(type default)
			)
			(layer "F.SilkS")
		)
		(fp_line
			(start 0.67945 0.3048)
			(end 0.120396 0.3048)
			(stroke
				(width 0.1)
				(type default)
			)
			(layer "F.Fab")
		)
		(fp_line
			(start 0.67945 -0.3048)
			(end 0.67945 0.3048)
			(stroke
				(width 0.1)
				(type default)
			)
			(layer "F.Fab")
		)
		(fp_line
			(start 0.12065 -0.2794)
			(end 0.12065 -0.3048)
			(stroke
				(width 0.1)
				(type default)
			)
			(layer "F.Fab")
		)
		(fp_line
			(start 0.12065 -0.3048)
			(end 0.67945 -0.3048)
			(stroke
				(width 0.1)
				(type default)
			)
			(layer "F.Fab")
		)
		(fp_line
			(start 0.120396 0.3048)
			(end 0.120396 0.2794)
			(stroke
				(width 0.1)
				(type default)
			)
			(layer "F.Fab")
		)
		(fp_line
			(start 0.120396 0.2794)
			(end -0.12065 0.2794)
			(stroke
				(width 0.1)
				(type default)
			)
			(layer "F.Fab")
		)
		(fp_line
			(start -0.12065 0.3048)
			(end -0.67945 0.3048)
			(stroke
				(width 0.1)
				(type default)
			)
			(layer "F.Fab")
		)
		(fp_line
			(start -0.12065 0.2794)
			(end -0.12065 0.3048)
			(stroke
				(width 0.1)
				(type default)
			)
			(layer "F.Fab")
		)
		(fp_line
			(start -0.12065 -0.2794)
			(end 0.12065 -0.2794)
			(stroke
				(width 0.1)
				(type default)
			)
			(layer "F.Fab")
		)
		(fp_line
			(start -0.12065 -0.305054)
			(end -0.12065 -0.2794)
			(stroke
				(width 0.1)
				(type default)
			)
			(layer "F.Fab")
		)
		(fp_line
			(start -0.67945 0.3048)
			(end -0.67945 -0.305054)
			(stroke
				(width 0.1)
				(type default)
			)
			(layer "F.Fab")
		)
		(fp_line
			(start -0.67945 -0.305054)
			(end -0.12065 -0.305054)
			(stroke
				(width 0.1)
				(type default)
			)
			(layer "F.Fab")
		)
		(pad "1" smd circle
			(at -0.40005 0 180)
			(size 0 0)
			(layers "F.Cu" "F.Mask" "F.Paste")
			(net "P3V3_AUX")
		)
		(pad "2" smd circle
			(at 0.40005 0 180)
			(size 0 0)
			(layers "F.Cu" "F.Mask" "F.Paste")
			(net "E1S_0_PRSNT_N")
		)
	)
)
